(kicad_pcb
	(version 20260206)
	(generator "pcbnew")
	(generator_version "10.0")
	(general
		(thickness 1.6)
		(legacy_teardrops no)
	)
	(paper "A4")
	(title_block
		(title "panther-plus-userver — 13130-1b_20150205.brd")
		(comment 1 "Honey Badger (Wiwynn) / footprints 528-535 of 1509")
	)
	(layers
		(0 "F.Cu" signal "TOP")
		(4 "In1.Cu" signal "L2")
		(6 "In2.Cu" signal "L3")
		(8 "In3.Cu" signal "L4")
		(10 "In4.Cu" signal "L5")
		(12 "In5.Cu" signal "L6")
		(14 "In6.Cu" signal "L7")
		(16 "In7.Cu" signal "L8")
		(18 "In8.Cu" signal "L9")
		(20 "In9.Cu" signal "L10")
		(22 "In10.Cu" signal "L11")
		(2 "B.Cu" signal "BOTTOM")
		(9 "F.Adhes" user "F.Adhesive")
		(11 "B.Adhes" user "B.Adhesive")
		(13 "F.Paste" user "Package Geometry/Pastemask Top")
		(15 "B.Paste" user "Package Geometry/Pastemask Bottom")
		(5 "F.SilkS" user "Ref Des/Silkscreen Top")
		(7 "B.SilkS" user "Ref Des/Silkscreen Bottom")
		(1 "F.Mask" user "Board Geometry/Soldermask Top")
		(3 "B.Mask" user "Board Geometry/Soldermask Bottom")
		(17 "Dwgs.User" user "User.Drawings")
		(19 "Cmts.User" user "User.Comments")
		(21 "Eco1.User" user "User.Eco1")
		(23 "Eco2.User" user "User.Eco2")
		(25 "Edge.Cuts" user "Board Geometry/Outline")
		(27 "Margin" user)
		(31 "F.CrtYd" user "Package Geometry/Place Bound Top")
		(29 "B.CrtYd" user "Package Geometry/Place Bound Bottom")
		(35 "F.Fab" user "Ref Des/Assembly Top")
		(33 "B.Fab" user "Ref Des/Assembly Bottom")
	)
	(footprint ""
		(layer "F.Cu")
		(at 159.7406 -44.8818 180)
		(property "Reference" "R215"
			(at 0 0 180)
			(layer "F.SilkS")
			(hide yes)
			(effects
				(font
					(size 1.27 1.27)
				)
			)
		)
		(property "Value" "0R2J-2-GP"
			(at 1.7907 -1.1176 180)
			(unlocked yes)
			(layer "F.Fab")
			(hide yes)
			(effects
				(font
					(size 1.016 1.016)
					(thickness 0.1524)
				)
			)
		)
		(property "Device Type" "R402H16"
			(at 1.7907 -2.6416 180)
			(unlocked yes)
			(layer "F.Fab")
			(hide yes)
			(effects
				(font
					(size 1.016 1.016)
					(thickness 0.1524)
				)
			)
		)
		(duplicate_pad_numbers_are_jumpers no)
		(fp_rect
			(start -0.381 0.8382)
			(end 0.381 -0.8382)
			(stroke
				(width 0)
				(type default)
			)
			(fill no)
			(layer "F.CrtYd")
		)
		(fp_rect
			(start -0.381 0.8382)
			(end 0.381 -0.8382)
			(stroke
				(width 0)
				(type default)
			)
			(fill no)
			(layer "F.Fab")
		)
		(pad "1" smd custom
			(at 0 -0.4318 180)
			(size 0.127 0.127)
			(layers "F.Cu" "F.Mask" "F.Paste")
			(net "JTAG_PLD_TCK")
			(options
				(clearance outline)
				(anchor circle)
			)
			(primitives
				(gr_poly
					(pts
						(arc
							(start -0.2032 -0.2794)
							(mid -0.239121 -0.264521)
							(end -0.254 -0.2286)
						)
						(arc
							(start -0.254 0.2286)
							(mid -0.239121 0.264521)
							(end -0.2032 0.2794)
						)
						(arc
							(start 0.2032 0.2794)
							(mid 0.239121 0.264521)
							(end 0.254 0.2286)
						)
						(arc
							(start 0.254 -0.2286)
							(mid 0.239121 -0.264521)
							(end 0.2032 -0.2794)
						)
					)
					(width 0)
					(fill yes)
				)
			)
		)
		(pad "2" smd custom
			(at 0 0.4318 180)
			(size 0.127 0.127)
			(layers "F.Cu" "F.Mask" "F.Paste")
			(net "JTAG_PLD_TCK_D")
			(options
				(clearance outline)
				(anchor circle)
			)
			(primitives
				(gr_poly
					(pts
						(arc
							(start -0.2032 -0.2794)
							(mid -0.239121 -0.264521)
							(end -0.254 -0.2286)
						)
						(arc
							(start -0.254 0.2286)
							(mid -0.239121 0.264521)
							(end -0.2032 0.2794)
						)
						(arc
							(start 0.2032 0.2794)
							(mid 0.239121 0.264521)
							(end 0.254 0.2286)
						)
						(arc
							(start 0.254 -0.2286)
							(mid 0.239121 -0.264521)
							(end 0.2032 -0.2794)
						)
					)
					(width 0)
					(fill yes)
				)
			)
		)
	)
	(footprint ""
		(layer "F.Cu")
		(at 74.041 -32.893 -90)
		(property "Reference" "R111"
			(at 0 0 270)
			(layer "F.SilkS")
			(hide yes)
			(effects
				(font
					(size 1.27 1.27)
				)
			)
		)
		(property "Value" "1KR2F-3-GP"
			(at 0.064008 -3.993896 270)
			(unlocked yes)
			(layer "F.Fab")
			(hide yes)
			(effects
				(font
					(size 1.016 1.016)
					(thickness 0.1524)
				)
			)
		)
		(property "Device Type" "R402H16"
			(at 0.064008 -5.517896 270)
			(unlocked yes)
			(layer "F.Fab")
			(hide yes)
			(effects
				(font
					(size 1.016 1.016)
					(thickness 0.1524)
				)
			)
		)
		(duplicate_pad_numbers_are_jumpers no)
		(fp_rect
			(start -0.381 0.8382)
			(end 0.381 -0.8382)
			(stroke
				(width 0)
				(type default)
			)
			(fill no)
			(layer "F.CrtYd")
		)
		(fp_rect
			(start -0.381 0.8382)
			(end 0.381 -0.8382)
			(stroke
				(width 0)
				(type default)
			)
			(fill no)
			(layer "F.Fab")
		)
		(pad "1" smd custom
			(at 0 -0.4318 270)
			(size 0.127 0.127)
			(layers "F.Cu" "F.Mask" "F.Paste")
			(net "SPI_CPU_CS0#")
			(options
				(clearance outline)
				(anchor circle)
			)
			(primitives
				(gr_poly
					(pts
						(arc
							(start -0.2032 -0.2794)
							(mid -0.239121 -0.264521)
							(end -0.254 -0.2286)
						)
						(arc
							(start -0.254 0.2286)
							(mid -0.239121 0.264521)
							(end -0.2032 0.2794)
						)
						(arc
							(start 0.2032 0.2794)
							(mid 0.239121 0.264521)
							(end 0.254 0.2286)
						)
						(arc
							(start 0.254 -0.2286)
							(mid 0.239121 -0.264521)
							(end 0.2032 -0.2794)
						)
					)
					(width 0)
					(fill yes)
				)
			)
		)
		(pad "2" smd custom
			(at 0 0.4318 270)
			(size 0.127 0.127)
			(layers "F.Cu" "F.Mask" "F.Paste")
			(net "GND")
			(options
				(clearance outline)
				(anchor circle)
			)
			(primitives
				(gr_poly
					(pts
						(arc
							(start -0.2032 -0.2794)
							(mid -0.239121 -0.264521)
							(end -0.254 -0.2286)
						)
						(arc
							(start -0.254 0.2286)
							(mid -0.239121 0.264521)
							(end -0.2032 0.2794)
						)
						(arc
							(start 0.2032 0.2794)
							(mid 0.239121 0.264521)
							(end 0.254 0.2286)
						)
						(arc
							(start 0.254 -0.2286)
							(mid 0.239121 -0.264521)
							(end 0.2032 -0.2794)
						)
					)
					(width 0)
					(fill yes)
				)
			)
		)
	)
	(footprint ""
		(layer "F.Cu")
		(at 46.863 -65.151)
		(property "Reference" "PC27"
			(at 0 0 0)
			(layer "F.SilkS")
			(hide yes)
			(effects
				(font
					(size 1.27 1.27)
				)
			)
		)
		(property "Value" "SC47U6D3V5MX-1-GP"
			(at 0 -4.9022 0)
			(unlocked yes)
			(layer "F.Fab")
			(hide yes)
			(effects
				(font
					(size 1.016 1.016)
					(thickness 0.1524)
				)
			)
		)
		(property "Device Type" "C805H54"
			(at 0 -6.8072 0)
			(unlocked yes)
			(layer "F.Fab")
			(hide yes)
			(effects
				(font
					(size 1.016 1.016)
					(thickness 0.1524)
				)
			)
		)
		(duplicate_pad_numbers_are_jumpers no)
		(fp_line
			(start 0.6096 0)
			(end -0.6096 0)
			(stroke
				(width 0.3048)
				(type default)
			)
			(layer "F.SilkS")
		)
		(fp_poly
			(pts
				(xy -0.9017 1.4351) (xy 0.9017 1.4351) (xy 0.9017 -1.4351) (xy -0.9017 -1.4351)
			)
			(stroke
				(width 0)
				(type default)
			)
			(fill no)
			(layer "F.CrtYd")
		)
		(fp_poly
			(pts
				(xy 0.9017 1.4351) (xy 0.9017 -1.4351) (xy -0.9017 -1.4351) (xy -0.9017 1.4351)
			)
			(stroke
				(width 0)
				(type default)
			)
			(fill no)
			(layer "F.Fab")
		)
		(pad "1" smd rect
			(at 0 -0.8382)
			(size 1.5494 0.9398)
			(layers "F.Cu" "F.Mask" "F.Paste")
			(net "PVNN")
		)
		(pad "2" smd rect
			(at 0 0.8382)
			(size 1.5494 0.9398)
			(layers "F.Cu" "F.Mask" "F.Paste")
			(net "GND")
		)
	)
	(footprint ""
		(layer "F.Cu")
		(at 136.271 -18.796)
		(property "Reference" "R58"
			(at 0 0 0)
			(layer "F.SilkS")
			(hide yes)
			(effects
				(font
					(size 1.27 1.27)
				)
			)
		)
		(property "Value" "0R2J-2-GP"
			(at 0.064008 -3.993896 0)
			(unlocked yes)
			(layer "F.Fab")
			(hide yes)
			(effects
				(font
					(size 1.016 1.016)
					(thickness 0.1524)
				)
			)
		)
		(property "Device Type" "R402H16"
			(at 0.064008 -5.517896 0)
			(unlocked yes)
			(layer "F.Fab")
			(hide yes)
			(effects
				(font
					(size 1.016 1.016)
					(thickness 0.1524)
				)
			)
		)
		(duplicate_pad_numbers_are_jumpers no)
		(fp_rect
			(start -0.381 0.8382)
			(end 0.381 -0.8382)
			(stroke
				(width 0)
				(type default)
			)
			(fill no)
			(layer "F.CrtYd")
		)
		(fp_rect
			(start -0.381 0.8382)
			(end 0.381 -0.8382)
			(stroke
				(width 0)
				(type default)
			)
			(fill no)
			(layer "F.Fab")
		)
		(pad "1" smd custom
			(at 0 -0.4318)
			(size 0.127 0.127)
			(layers "F.Cu" "F.Mask" "F.Paste")
			(net "HOST_RSTBTN#")
			(options
				(clearance outline)
				(anchor circle)
			)
			(primitives
				(gr_poly
					(pts
						(arc
							(start -0.2032 -0.2794)
							(mid -0.239121 -0.264521)
							(end -0.254 -0.2286)
						)
						(arc
							(start -0.254 0.2286)
							(mid -0.239121 0.264521)
							(end -0.2032 0.2794)
						)
						(arc
							(start 0.2032 0.2794)
							(mid 0.239121 0.264521)
							(end 0.254 0.2286)
						)
						(arc
							(start 0.254 -0.2286)
							(mid 0.239121 -0.264521)
							(end 0.2032 -0.2794)
						)
					)
					(width 0)
					(fill yes)
				)
			)
		)
		(pad "2" smd custom
			(at 0 0.4318)
			(size 0.127 0.127)
			(layers "F.Cu" "F.Mask" "F.Paste")
			(net "HOST_R_RSTBTN#")
			(options
				(clearance outline)
				(anchor circle)
			)
			(primitives
				(gr_poly
					(pts
						(arc
							(start -0.2032 -0.2794)
							(mid -0.239121 -0.264521)
							(end -0.254 -0.2286)
						)
						(arc
							(start -0.254 0.2286)
							(mid -0.239121 0.264521)
							(end -0.2032 0.2794)
						)
						(arc
							(start 0.2032 0.2794)
							(mid 0.239121 0.264521)
							(end 0.254 0.2286)
						)
						(arc
							(start 0.254 -0.2286)
							(mid 0.239121 -0.264521)
							(end 0.2032 -0.2794)
						)
					)
					(width 0)
					(fill yes)
				)
			)
		)
	)
	(footprint ""
		(layer "F.Cu")
		(at 186.309 -43.307)
		(property "Reference" "C96"
			(at 0 0 0)
			(layer "F.SilkS")
			(hide yes)
			(effects
				(font
					(size 1.27 1.27)
				)
			)
		)
		(property "Value" "SC1U6D3V2KX-GP"
			(at 1.1811 -2.7051 0)
			(unlocked yes)
			(layer "F.Fab")
			(hide yes)
			(effects
				(font
					(size 1.016 1.016)
					(thickness 0.1524)
				)
			)
		)
		(property "Device Type" "C402H22"
			(at 1.1811 -4.2291 0)
			(unlocked yes)
			(layer "F.Fab")
			(hide yes)
			(effects
				(font
					(size 1.016 1.016)
					(thickness 0.1524)
				)
			)
		)
		(duplicate_pad_numbers_are_jumpers no)
		(fp_rect
			(start -0.381 0.7366)
			(end 0.381 -0.7366)
			(stroke
				(width 0)
				(type default)
			)
			(fill no)
			(layer "F.CrtYd")
		)
		(fp_rect
			(start -0.381 0.7366)
			(end 0.381 -0.7366)
			(stroke
				(width 0)
				(type default)
			)
			(fill no)
			(layer "F.Fab")
		)
		(pad "1" smd custom
			(at 0 -0.4572)
			(size 0.1143 0.1143)
			(layers "F.Cu" "F.Mask" "F.Paste")
			(net "PV_VDDR_VREF_B")
			(options
				(clearance outline)
				(anchor circle)
			)
			(primitives
				(gr_poly
					(pts
						(arc
							(start -0.254 -0.1778)
							(mid -0.239121 -0.213721)
							(end -0.2032 -0.2286)
						)
						(arc
							(start 0.2032 -0.2286)
							(mid 0.239121 -0.213721)
							(end 0.254 -0.1778)
						)
						(arc
							(start 0.254 0.1778)
							(mid 0.239121 0.213721)
							(end 0.2032 0.2286)
						)
						(arc
							(start -0.2032 0.2286)
							(mid -0.239121 0.213721)
							(end -0.254 0.1778)
						)
					)
					(width 0)
					(fill yes)
				)
			)
		)
		(pad "2" smd custom
			(at 0 0.4572)
			(size 0.1143 0.1143)
			(layers "F.Cu" "F.Mask" "F.Paste")
			(net "GND")
			(options
				(clearance outline)
				(anchor circle)
			)
			(primitives
				(gr_poly
					(pts
						(arc
							(start -0.254 -0.1778)
							(mid -0.239121 -0.213721)
							(end -0.2032 -0.2286)
						)
						(arc
							(start 0.2032 -0.2286)
							(mid 0.239121 -0.213721)
							(end 0.254 -0.1778)
						)
						(arc
							(start 0.254 0.1778)
							(mid 0.239121 0.213721)
							(end 0.2032 0.2286)
						)
						(arc
							(start -0.2032 0.2286)
							(mid -0.239121 0.213721)
							(end -0.254 0.1778)
						)
					)
					(width 0)
					(fill yes)
				)
			)
		)
	)
	(footprint ""
		(layer "F.Cu")
		(at 183.3118 -31.7246)
		(property "Reference" "PR150"
			(at 0 0 0)
			(layer "F.SilkS")
			(hide yes)
			(effects
				(font
					(size 1.27 1.27)
				)
			)
		)
		(property "Value" "15KR2J-1-GP"
			(at 1.7907 -1.1176 0)
			(unlocked yes)
			(layer "F.Fab")
			(hide yes)
			(effects
				(font
					(size 1.016 1.016)
					(thickness 0.1524)
				)
			)
		)
		(property "Device Type" "R402H16"
			(at 1.7907 -2.6416 0)
			(unlocked yes)
			(layer "F.Fab")
			(hide yes)
			(effects
				(font
					(size 1.016 1.016)
					(thickness 0.1524)
				)
			)
		)
		(duplicate_pad_numbers_are_jumpers no)
		(fp_rect
			(start -0.381 0.8382)
			(end 0.381 -0.8382)
			(stroke
				(width 0)
				(type default)
			)
			(fill no)
			(layer "F.CrtYd")
		)
		(fp_rect
			(start -0.381 0.8382)
			(end 0.381 -0.8382)
			(stroke
				(width 0)
				(type default)
			)
			(fill no)
			(layer "F.Fab")
		)
		(pad "1" smd custom
			(at 0 -0.4318)
			(size 0.127 0.127)
			(layers "F.Cu" "F.Mask" "F.Paste")
			(net "VR_PVDDR_A_VW")
			(options
				(clearance outline)
				(anchor circle)
			)
			(primitives
				(gr_poly
					(pts
						(arc
							(start -0.2032 -0.2794)
							(mid -0.239121 -0.264521)
							(end -0.254 -0.2286)
						)
						(arc
							(start -0.254 0.2286)
							(mid -0.239121 0.264521)
							(end -0.2032 0.2794)
						)
						(arc
							(start 0.2032 0.2794)
							(mid 0.239121 0.264521)
							(end 0.254 0.2286)
						)
						(arc
							(start 0.254 -0.2286)
							(mid 0.239121 -0.264521)
							(end 0.2032 -0.2794)
						)
					)
					(width 0)
					(fill yes)
				)
			)
		)
		(pad "2" smd custom
			(at 0 0.4318)
			(size 0.127 0.127)
			(layers "F.Cu" "F.Mask" "F.Paste")
			(net "VR_PVDDR_A_COMP")
			(options
				(clearance outline)
				(anchor circle)
			)
			(primitives
				(gr_poly
					(pts
						(arc
							(start -0.2032 -0.2794)
							(mid -0.239121 -0.264521)
							(end -0.254 -0.2286)
						)
						(arc
							(start -0.254 0.2286)
							(mid -0.239121 0.264521)
							(end -0.2032 0.2794)
						)
						(arc
							(start 0.2032 0.2794)
							(mid 0.239121 0.264521)
							(end 0.254 0.2286)
						)
						(arc
							(start 0.254 -0.2286)
							(mid 0.239121 -0.264521)
							(end 0.2032 -0.2794)
						)
					)
					(width 0)
					(fill yes)
				)
			)
		)
	)
	(footprint ""
		(layer "F.Cu")
		(at 150.241 -20.701)
		(property "Reference" "C49"
			(at 0 0 0)
			(layer "F.SilkS")
			(hide yes)
			(effects
				(font
					(size 1.27 1.27)
				)
			)
		)
		(property "Value" "SCD1U10V2KX-5GP"
			(at 1.1811 -2.7051 0)
			(unlocked yes)
			(layer "F.Fab")
			(hide yes)
			(effects
				(font
					(size 1.016 1.016)
					(thickness 0.1524)
				)
			)
		)
		(property "Device Type" "C402H22"
			(at 1.1811 -4.2291 0)
			(unlocked yes)
			(layer "F.Fab")
			(hide yes)
			(effects
				(font
					(size 1.016 1.016)
					(thickness 0.1524)
				)
			)
		)
		(duplicate_pad_numbers_are_jumpers no)
		(fp_rect
			(start -0.381 0.7366)
			(end 0.381 -0.7366)
			(stroke
				(width 0)
				(type default)
			)
			(fill no)
			(layer "F.CrtYd")
		)
		(fp_rect
			(start -0.381 0.7366)
			(end 0.381 -0.7366)
			(stroke
				(width 0)
				(type default)
			)
			(fill no)
			(layer "F.Fab")
		)
		(pad "1" smd custom
			(at 0 -0.4572)
			(size 0.1143 0.1143)
			(layers "F.Cu" "F.Mask" "F.Paste")
			(net "P2V5_STBY")
			(options
				(clearance outline)
				(anchor circle)
			)
			(primitives
				(gr_poly
					(pts
						(arc
							(start -0.254 -0.1778)
							(mid -0.239121 -0.213721)
							(end -0.2032 -0.2286)
						)
						(arc
							(start 0.2032 -0.2286)
							(mid 0.239121 -0.213721)
							(end 0.254 -0.1778)
						)
						(arc
							(start 0.254 0.1778)
							(mid 0.239121 0.213721)
							(end 0.2032 0.2286)
						)
						(arc
							(start -0.2032 0.2286)
							(mid -0.239121 0.213721)
							(end -0.254 0.1778)
						)
					)
					(width 0)
					(fill yes)
				)
			)
		)
		(pad "2" smd custom
			(at 0 0.4572)
			(size 0.1143 0.1143)
			(layers "F.Cu" "F.Mask" "F.Paste")
			(net "GND")
			(options
				(clearance outline)
				(anchor circle)
			)
			(primitives
				(gr_poly
					(pts
						(arc
							(start -0.254 -0.1778)
							(mid -0.239121 -0.213721)
							(end -0.2032 -0.2286)
						)
						(arc
							(start 0.2032 -0.2286)
							(mid 0.239121 -0.213721)
							(end 0.254 -0.1778)
						)
						(arc
							(start 0.254 0.1778)
							(mid 0.239121 0.213721)
							(end 0.2032 0.2286)
						)
						(arc
							(start -0.2032 0.2286)
							(mid -0.239121 0.213721)
							(end -0.254 0.1778)
						)
					)
					(width 0)
					(fill yes)
				)
			)
		)
	)
	(footprint ""
		(layer "F.Cu")
		(at 54.2544 -19.6596 -90)
		(property "Reference" "U21"
			(at 0 0 270)
			(layer "F.SilkS")
			(hide yes)
			(effects
				(font
					(size 1.27 1.27)
				)
			)
		)
		(property "Value" "AT25256B-SSHL-T-GP"
			(at -3.707384 -1.5367 270)
			(unlocked yes)
			(layer "F.Fab")
			(hide yes)
			(effects
				(font
					(size 1.016 1.016)
					(thickness 0.1524)
				)
			)
		)
		(property "Device Type" "SOIC8H69"
			(at -3.707384 -3.0607 270)
			(unlocked yes)
			(layer "F.Fab")
			(hide yes)
			(effects
				(font
					(size 1.016 1.016)
					(thickness 0.1524)
				)
			)
		)
		(duplicate_pad_numbers_are_jumpers no)
		(fp_line
			(start -2.6797 1.4351)
			(end 2.1463 1.4351)
			(stroke
				(width 0.1524)
				(type default)
			)
			(layer "F.SilkS")
		)
		(fp_line
			(start 2.1463 1.4351)
			(end 2.1463 -1.4351)
			(stroke
				(width 0.1524)
				(type default)
			)
			(layer "F.SilkS")
		)
		(fp_line
			(start -2.502154 1.4224)
			(end -2.502154 3.1115)
			(stroke
				(width 0.508)
				(type default)
			)
			(layer "F.SilkS")
		)
		(fp_line
			(start -2.6797 0.508)
			(end -2.1717 0)
			(stroke
				(width 0.1524)
				(type default)
			)
			(layer "F.SilkS")
		)
		(fp_line
			(start -2.1717 0)
			(end -2.6797 -0.508)
			(stroke
				(width 0.1524)
				(type default)
			)
			(layer "F.SilkS")
		)
		(fp_line
			(start -2.6797 -0.508)
			(end -2.6797 0.508)
			(stroke
				(width 0.1524)
				(type default)
			)
			(layer "F.SilkS")
		)
		(fp_line
			(start -2.6797 -1.4351)
			(end -2.6797 1.4351)
			(stroke
				(width 0.1524)
				(type default)
			)
			(layer "F.SilkS")
		)
		(fp_line
			(start 2.1463 -1.4351)
			(end -2.6797 -1.4351)
			(stroke
				(width 0.1524)
				(type default)
			)
			(layer "F.SilkS")
		)
		(fp_poly
			(pts
				(xy -2.2225 -1.4351) (xy -2.2225 1.4351) (xy 2.1463 1.4351) (xy 2.1463 -1.4351)
			)
			(stroke
				(width 0)
				(type default)
			)
			(fill yes)
			(layer "F.SilkS")
		)
		(fp_rect
			(start -2.7559 3.3655)
			(end 2.7559 -3.3655)
			(stroke
				(width 0)
				(type default)
			)
			(fill no)
			(layer "F.CrtYd")
		)
		(fp_rect
			(start -2.7559 3.3655)
			(end 2.7559 -3.3655)
			(stroke
				(width 0)
				(type default)
			)
			(fill no)
			(layer "F.Fab")
		)
		(pad "1" smd rect
			(at -1.905 2.4765 270)
			(size 0.635 1.524)
			(layers "F.Cu" "F.Mask" "F.Paste")
			(net "SPI_CS_GBE#")
		)
		(pad "2" smd rect
			(at -0.635 2.4765 270)
			(size 0.635 1.524)
			(layers "F.Cu" "F.Mask" "F.Paste")
			(net "SO_GBE")
		)
		(pad "3" smd rect
			(at 0.635 2.4765 270)
			(size 0.635 1.524)
			(layers "F.Cu" "F.Mask" "F.Paste")
			(net "SPI_GBE_HOLD#")
		)
		(pad "4" smd rect
			(at 1.905 2.4765 270)
			(size 0.635 1.524)
			(layers "F.Cu" "F.Mask" "F.Paste")
			(net "GND")
		)
		(pad "5" smd rect
			(at 1.905 -2.4765 270)
			(size 0.635 1.524)
			(layers "F.Cu" "F.Mask" "F.Paste")
			(net "SPI_MOSI_GBE_R")
		)
		(pad "6" smd rect
			(at 0.635 -2.4765 270)
			(size 0.635 1.524)
			(layers "F.Cu" "F.Mask" "F.Paste")
			(net "SPI_CLK_GBE_R")
		)
		(pad "7" smd rect
			(at -0.635 -2.4765 270)
			(size 0.635 1.524)
			(layers "F.Cu" "F.Mask" "F.Paste")
			(net "SPI_GBE_HOLD#")
		)
		(pad "8" smd rect
			(at -1.905 -2.4765 270)
			(size 0.635 1.524)
			(layers "F.Cu" "F.Mask" "F.Paste")
			(net "P3V3_CPU")
		)
	)
)
